G04 ================== begin FILE IDENTIFICATION RECORD ==================*
G04 Layout Name:  14629-1a.brd*
G04 Film Name:    BMASK*
G04 File Format:  Gerber RS274X*
G04 File Origin:  Cadence Allegro 16.5-S037*
G04 Origin Date:  Tue Nov 25 11:50:35 2014*
G04 *
G04 Layer:  VIA CLASS/SOLDERMASK_BOTTOM*
G04 Layer:  PIN/SOLDERMASK_BOTTOM*
G04 Layer:  PACKAGE GEOMETRY/SOLDERMASK_BOTTOM*
G04 Layer:  DRAWING FORMAT/LAYER_PCB_STORY*
G04 Layer:  DRAWING FORMAT/LAYER_SOLDER_B*
G04 Layer:  BOARD GEOMETRY/SOLDERMASK_BOTTOM*
G04 *
G04 Offset:    (0.00 0.00)*
G04 Mirror:    No*
G04 Mode:      Positive*
G04 Rotation:  0*
G04 FullContactRelief:  No*
G04 UndefLineWidth:     6.00*
G04 ================== end FILE IDENTIFICATION RECORD ====================*
%FSLAX35Y35*MOIN*%
%IR0*IPPOS*OFA0.00000B0.00000*MIA0B0*SFA1.00000B1.00000*%
%ADD19C,.052*%
%ADD14R,.197X.032*%
%ADD12C,.08*%
%ADD18C,.064*%
%ADD16C,.028*%
%ADD17C,.057*%
%ADD10C,.086*%
%ADD15R,.248X.165*%
%ADD13R,.248X.372*%
%ADD11C,.355*%
%ADD20C,.158*%
%ADD21C,.02*%
%ADD22C,.006*%
G75*
%LPD*%
G75*
G36*
G01X-43611Y110602D02*
X-12605D01*
Y291274D01*
X-17705D01*
Y366242D01*
X-43611D01*
Y110602D01*
G37*
G54D10*
X-23621Y15748D03*
Y937008D03*
X1312285Y15747D03*
X1312281Y889328D03*
G54D20*
X600709Y136909D03*
Y311909D03*
G54D11*
X30157Y61023D03*
Y415354D03*
X498661Y23622D03*
X518346Y448818D03*
G54D21*
G01X-4246Y-109426D02*
Y-189426D01*
G01D02*
X1290354D01*
G01X-4246Y-144926D02*
X1290354D01*
G01X-8246Y-93426D02*
G02I-12000J0D01*
G01X-13396D02*
G02I-6850J0D01*
G01X-20246Y-109426D02*
Y-77426D01*
G01X-4246Y-93426D02*
X-36246D01*
G01X-4246Y-109426D02*
X1290354D01*
G01X502854D02*
Y-189426D01*
G01X640354Y-109426D02*
Y-189426D01*
G01X755354Y-109426D02*
Y-189426D01*
G01X922854Y-109426D02*
Y-189426D01*
G01X1092854Y-109426D02*
Y-189426D01*
G01X1290354Y-109426D02*
Y-189426D01*
G01X1318354Y-93426D02*
G02I-12000J0D01*
G01X1313204D02*
G02I-6850J0D01*
G01X1306354Y-109426D02*
Y-77426D01*
G01X1322354Y-93426D02*
X1290354D01*
G54D12*
X-23622Y62794D03*
Y916269D03*
X1297695Y58466D03*
G54D22*
G01X121969Y-179426D02*
Y-161926D01*
G01X131139D02*
Y-179426D01*
G01Y-170676D02*
X121969D01*
G01X144054Y-179426D02*
X142744Y-179134D01*
X141434Y-177968D01*
X140560Y-175926D01*
X140124Y-173593D01*
X140560Y-171259D01*
X141434Y-169218D01*
X142744Y-168051D01*
X144054Y-167760D01*
X145364Y-168051D01*
X146674Y-169218D01*
X147547Y-171259D01*
X147766Y-173593D01*
X147547Y-175926D01*
X146674Y-177968D01*
X145364Y-179134D01*
X144054Y-179426D01*
G01X157842D02*
Y-167760D01*
G01Y-170676D02*
X158716Y-169218D01*
X160026Y-168051D01*
X161772Y-167760D01*
X163300Y-168051D01*
X164611Y-169218D01*
X165266Y-171259D01*
Y-179426D01*
G01X175779Y-171551D02*
X182766D01*
X182111Y-169509D01*
X181019Y-168343D01*
X179491Y-167760D01*
X177962Y-168051D01*
X176652Y-168926D01*
X175779Y-170968D01*
X175342Y-172718D01*
Y-174468D01*
X175779Y-176218D01*
X176871Y-177968D01*
X178181Y-179134D01*
X179709Y-179426D01*
X181237Y-178843D01*
X182766Y-177093D01*
G01X191969Y-184676D02*
X193279Y-185259D01*
X195026Y-184676D01*
X196117Y-183510D01*
X196991Y-182051D01*
X198300Y-177385D01*
X201139Y-167760D01*
G01X194152D02*
X198300Y-177385D01*
G01X233300Y-170093D02*
X234174Y-169218D01*
X234829Y-167760D01*
X235266Y-165717D01*
X234829Y-163968D01*
X233956Y-162801D01*
X232427Y-161926D01*
X226532D01*
Y-179426D01*
X233737D01*
X235266Y-178260D01*
X236139Y-176509D01*
X236576Y-174468D01*
X236139Y-172426D01*
X234829Y-170676D01*
X233300Y-170093D01*
X226532D01*
G01X252984Y-179426D02*
Y-167760D01*
G01Y-169801D02*
X252111Y-168635D01*
X250800Y-168051D01*
X249272Y-167760D01*
X247744Y-168343D01*
X246434Y-169509D01*
X245560Y-171259D01*
X245124Y-173593D01*
X245560Y-175926D01*
X246434Y-177676D01*
X247744Y-178843D01*
X249272Y-179426D01*
X250800Y-179134D01*
X252111Y-178260D01*
X252984Y-177093D01*
G01X270484Y-161926D02*
Y-179426D01*
G01Y-176802D02*
X269611Y-178260D01*
X268300Y-179134D01*
X266772Y-179426D01*
X265026Y-178843D01*
X263716Y-177385D01*
X262842Y-175635D01*
X262624Y-173593D01*
X262842Y-171551D01*
X263716Y-169801D01*
X265026Y-168343D01*
X266772Y-167760D01*
X268300Y-168051D01*
X269392Y-168635D01*
X270484Y-169801D01*
G01X280997Y-183801D02*
X282526Y-184968D01*
X284272Y-185259D01*
X285800Y-184968D01*
X287111Y-183510D01*
X287984Y-181468D01*
Y-167760D01*
G01Y-170093D02*
X287111Y-168926D01*
X285800Y-168051D01*
X284272Y-167760D01*
X282526Y-168343D01*
X281434Y-169509D01*
X280560Y-171551D01*
X280124Y-173593D01*
X280342Y-175343D01*
X281216Y-177385D01*
X282526Y-178843D01*
X284272Y-179426D01*
X285582Y-179134D01*
X287111Y-177968D01*
X287984Y-176802D01*
G01X298279Y-171551D02*
X305266D01*
X304611Y-169509D01*
X303519Y-168343D01*
X301991Y-167760D01*
X300462Y-168051D01*
X299152Y-168926D01*
X298279Y-170968D01*
X297842Y-172718D01*
Y-174468D01*
X298279Y-176218D01*
X299371Y-177968D01*
X300681Y-179134D01*
X302209Y-179426D01*
X303737Y-178843D01*
X305266Y-177093D01*
G01X315997Y-179426D02*
Y-167760D01*
G01Y-170093D02*
X317089Y-168926D01*
X318181Y-168051D01*
X319709Y-167760D01*
X320800Y-168051D01*
X322111Y-168926D01*
G01X349687Y-179426D02*
Y-161926D01*
X354927D01*
X356674Y-162801D01*
X357984Y-164843D01*
X358421Y-167176D01*
X357984Y-169509D01*
X356892Y-171259D01*
X354927Y-172135D01*
X349687D01*
G01X371554Y-161926D02*
Y-179426D01*
G01X366532Y-161926D02*
X376576D01*
G01X390800Y-170093D02*
X391674Y-169218D01*
X392329Y-167760D01*
X392766Y-165717D01*
X392329Y-163968D01*
X391456Y-162801D01*
X389927Y-161926D01*
X384032D01*
Y-179426D01*
X391237D01*
X392766Y-178260D01*
X393639Y-176509D01*
X394076Y-174468D01*
X393639Y-172426D01*
X392329Y-170676D01*
X390800Y-170093D01*
X384032D01*
G01X208377Y-134426D02*
Y-116926D01*
X214054Y-131509D01*
X219731Y-116926D01*
Y-134426D01*
G01X231554D02*
X230244Y-134134D01*
X228934Y-132968D01*
X228060Y-130926D01*
X227624Y-128593D01*
X228060Y-126259D01*
X228934Y-124218D01*
X230244Y-123051D01*
X231554Y-122760D01*
X232864Y-123051D01*
X234174Y-124218D01*
X235047Y-126259D01*
X235266Y-128593D01*
X235047Y-130926D01*
X234174Y-132968D01*
X232864Y-134134D01*
X231554Y-134426D01*
G01X252984Y-116926D02*
Y-134426D01*
G01Y-131802D02*
X252111Y-133260D01*
X250800Y-134134D01*
X249272Y-134426D01*
X247526Y-133843D01*
X246216Y-132385D01*
X245342Y-130635D01*
X245124Y-128593D01*
X245342Y-126551D01*
X246216Y-124801D01*
X247526Y-123343D01*
X249272Y-122760D01*
X250800Y-123051D01*
X251892Y-123635D01*
X252984Y-124801D01*
G01X263279Y-126551D02*
X270266D01*
X269611Y-124509D01*
X268519Y-123343D01*
X266991Y-122760D01*
X265462Y-123051D01*
X264152Y-123926D01*
X263279Y-125968D01*
X262842Y-127718D01*
Y-129468D01*
X263279Y-131218D01*
X264371Y-132968D01*
X265681Y-134134D01*
X267209Y-134426D01*
X268737Y-133843D01*
X270266Y-132093D01*
G01X284054Y-134426D02*
Y-116926D01*
G01X536554Y-179426D02*
Y-161926D01*
X533934Y-165426D01*
G01Y-179426D02*
X539174D01*
G01X556674D02*
Y-161926D01*
X548595Y-174468D01*
X559513D01*
G01X567406Y-172135D02*
X568934Y-170093D01*
X570244Y-168926D01*
X571991Y-168343D01*
X573519Y-168926D01*
X574611Y-170093D01*
X575484Y-171843D01*
X575702Y-173884D01*
X575484Y-175635D01*
X574611Y-177385D01*
X573300Y-178843D01*
X571772Y-179426D01*
X570026Y-178843D01*
X568497Y-177093D01*
X567624Y-174468D01*
X567406Y-171551D01*
X567842Y-167760D01*
X568497Y-165717D01*
X569589Y-163676D01*
X571117Y-162218D01*
X572646Y-161926D01*
X574174Y-162509D01*
X575266Y-163968D01*
G01X584906Y-164843D02*
X586216Y-163093D01*
X587744Y-162218D01*
X589491Y-161926D01*
X591674Y-162509D01*
X593202Y-163968D01*
X593639Y-165717D01*
X593421Y-167468D01*
X592547Y-168926D01*
X588181Y-171843D01*
X586216Y-173884D01*
X584906Y-176802D01*
X584469Y-179426D01*
X593639D01*
G01X602842Y-177385D02*
X604371Y-178843D01*
X606117Y-179426D01*
X607864Y-178843D01*
X609392Y-177093D01*
X610484Y-174468D01*
X610921Y-171843D01*
Y-168635D01*
X610484Y-166010D01*
X609392Y-163676D01*
X608082Y-162509D01*
X606554Y-161926D01*
X604807Y-162509D01*
X603497Y-163676D01*
X602624Y-165426D01*
X602187Y-167760D01*
X602624Y-169801D01*
X603716Y-171843D01*
X605026Y-173010D01*
X606554Y-173301D01*
X608300Y-172718D01*
X609611Y-171259D01*
X610921Y-168635D01*
G01X523437Y-134426D02*
Y-116926D01*
X528677D01*
X530424Y-117801D01*
X531734Y-119843D01*
X532171Y-122176D01*
X531734Y-124509D01*
X530642Y-126259D01*
X528677Y-127135D01*
X523437D01*
G01X550107Y-118385D02*
X548797Y-117509D01*
X547269Y-116926D01*
X545522D01*
X543557Y-117801D01*
X542029Y-119259D01*
X540937Y-121010D01*
X540064Y-123926D01*
X539845Y-126551D01*
X540282Y-129176D01*
X540937Y-130926D01*
X542247Y-132676D01*
X543776Y-133843D01*
X545304Y-134426D01*
X546832D01*
X548361Y-133843D01*
X549671Y-132968D01*
X550763Y-131802D01*
G01X564550Y-125093D02*
X565424Y-124218D01*
X566079Y-122760D01*
X566516Y-120717D01*
X566079Y-118968D01*
X565206Y-117801D01*
X563677Y-116926D01*
X557782D01*
Y-134426D01*
X564987D01*
X566516Y-133260D01*
X567389Y-131509D01*
X567826Y-129468D01*
X567389Y-127426D01*
X566079Y-125676D01*
X564550Y-125093D01*
X557782D01*
G01X573754Y-140259D02*
X586854D01*
G01X592782Y-134426D02*
Y-116926D01*
X602826Y-134426D01*
Y-116926D01*
G01X615304Y-134426D02*
X613557Y-134134D01*
X612029Y-132968D01*
X610719Y-131218D01*
X609845Y-129176D01*
X609409Y-126843D01*
Y-124509D01*
X609845Y-122176D01*
X610719Y-120134D01*
X612029Y-118385D01*
X613557Y-117218D01*
X615304Y-116926D01*
X617050Y-117218D01*
X618579Y-118385D01*
X619889Y-120134D01*
X620763Y-122176D01*
X621199Y-124509D01*
Y-126843D01*
X620763Y-129176D01*
X619889Y-131218D01*
X618579Y-132968D01*
X617050Y-134134D01*
X615304Y-134426D01*
G01X689104Y-179426D02*
Y-161926D01*
X686484Y-165426D01*
G01Y-179426D02*
X691724D01*
G01X701145D02*
X706604Y-161926D01*
X712063Y-179426D01*
G01X710097Y-173301D02*
X703110D01*
G01X666145Y-116926D02*
X671604Y-134426D01*
X677063Y-116926D01*
G01X693471Y-134426D02*
X684737D01*
Y-116926D01*
X693471D01*
G01X689977Y-125384D02*
X684737D01*
G01X702237Y-134426D02*
Y-116926D01*
X707696D01*
X709442Y-117801D01*
X710534Y-118968D01*
X710971Y-121301D01*
X710534Y-123635D01*
X709224Y-125093D01*
X707696Y-125968D01*
X702237D01*
G01X707696D02*
X710971Y-134426D01*
G01X724104Y-135009D02*
X723667Y-134718D01*
Y-134134D01*
X724104Y-133843D01*
X724541Y-134134D01*
Y-134718D01*
X724104Y-135009D01*
G01X872308Y-170093D02*
X871434Y-169218D01*
X870779Y-167760D01*
X870342Y-165717D01*
X870779Y-163968D01*
X871652Y-162801D01*
X873181Y-161926D01*
X879076D01*
Y-179426D01*
X871871D01*
X870342Y-178260D01*
X869469Y-176509D01*
X869032Y-174468D01*
X869469Y-172426D01*
X870779Y-170676D01*
X872308Y-170093D01*
X879076D01*
G01X862231Y-179426D02*
Y-161926D01*
X856554Y-176509D01*
X850877Y-161926D01*
Y-179426D01*
G01X844513D02*
X839054Y-161926D01*
X833595Y-179426D01*
G01X835561Y-173301D02*
X842548D01*
G01X826139Y-177093D02*
X824392Y-178551D01*
X822427Y-179426D01*
X820681D01*
X818934Y-178551D01*
X817624Y-177093D01*
X816969Y-175051D01*
X817406Y-173010D01*
X818497Y-171259D01*
X820462Y-170093D01*
X823082Y-169509D01*
X824611Y-168343D01*
X825266Y-166301D01*
X824829Y-164259D01*
X823737Y-162801D01*
X822209Y-161926D01*
X820681D01*
X819152Y-162509D01*
X817842Y-163968D01*
G01X808857Y-179426D02*
Y-161926D01*
G01X800561D02*
X808857Y-172718D01*
G01X799251Y-179426D02*
X805146Y-167760D01*
G01X790937Y-116926D02*
Y-134426D01*
X799671D01*
G01X816734D02*
Y-122760D01*
G01Y-124801D02*
X815861Y-123635D01*
X814550Y-123051D01*
X813022Y-122760D01*
X811494Y-123343D01*
X810184Y-124509D01*
X809310Y-126259D01*
X808874Y-128593D01*
X809310Y-130926D01*
X810184Y-132676D01*
X811494Y-133843D01*
X813022Y-134426D01*
X814550Y-134134D01*
X815861Y-133260D01*
X816734Y-132093D01*
G01X825719Y-139676D02*
X827029Y-140259D01*
X828776Y-139676D01*
X829867Y-138510D01*
X830741Y-137051D01*
X832050Y-132385D01*
X834889Y-122760D01*
G01X827902D02*
X832050Y-132385D01*
G01X844529Y-126551D02*
X851516D01*
X850861Y-124509D01*
X849769Y-123343D01*
X848241Y-122760D01*
X846712Y-123051D01*
X845402Y-123926D01*
X844529Y-125968D01*
X844092Y-127718D01*
Y-129468D01*
X844529Y-131218D01*
X845621Y-132968D01*
X846931Y-134134D01*
X848459Y-134426D01*
X849987Y-133843D01*
X851516Y-132093D01*
G01X862247Y-134426D02*
Y-122760D01*
G01Y-125093D02*
X863339Y-123926D01*
X864431Y-123051D01*
X865959Y-122760D01*
X867050Y-123051D01*
X868361Y-123926D01*
G01X879529Y-132385D02*
X880621Y-133551D01*
X882149Y-134426D01*
X883459D01*
X884769Y-133843D01*
X885642Y-132968D01*
X886079Y-131802D01*
X885861Y-130051D01*
X884987Y-129176D01*
X881057Y-127426D01*
X880184Y-125384D01*
X880621Y-123926D01*
X881494Y-123051D01*
X882804Y-122760D01*
X884114Y-123051D01*
X885424Y-123926D01*
G01X924737Y-175926D02*
X925829Y-177676D01*
X927139Y-178843D01*
X928667Y-179426D01*
X930414Y-178843D01*
X931724Y-177676D01*
X933034Y-175926D01*
X933471Y-173593D01*
Y-161926D01*
G01X946604Y-179426D02*
X944857Y-179134D01*
X943329Y-177968D01*
X942019Y-176218D01*
X941145Y-174176D01*
X940709Y-171843D01*
Y-169509D01*
X941145Y-167176D01*
X942019Y-165134D01*
X943329Y-163385D01*
X944857Y-162218D01*
X946604Y-161926D01*
X948350Y-162218D01*
X949879Y-163385D01*
X951189Y-165134D01*
X952063Y-167176D01*
X952499Y-169509D01*
Y-171843D01*
X952063Y-174176D01*
X951189Y-176218D01*
X949879Y-177968D01*
X948350Y-179134D01*
X946604Y-179426D01*
G01X959519Y-177093D02*
X961266Y-178551D01*
X963231Y-179426D01*
X964977D01*
X966724Y-178551D01*
X968034Y-177093D01*
X968689Y-175051D01*
X968252Y-173010D01*
X967161Y-171259D01*
X965196Y-170093D01*
X962576Y-169509D01*
X961047Y-168343D01*
X960392Y-166301D01*
X960829Y-164259D01*
X961921Y-162801D01*
X963449Y-161926D01*
X964977D01*
X966506Y-162509D01*
X967816Y-163968D01*
G01X985971Y-179426D02*
X977237D01*
Y-161926D01*
X985971D01*
G01X982477Y-170384D02*
X977237D01*
G01X994737Y-179426D02*
Y-161926D01*
X999977D01*
X1001724Y-162801D01*
X1003034Y-164843D01*
X1003471Y-167176D01*
X1003034Y-169509D01*
X1001942Y-171259D01*
X999977Y-172135D01*
X994737D01*
G01X1012019Y-179426D02*
Y-161926D01*
G01X1021189D02*
Y-179426D01*
G01Y-170676D02*
X1012019D01*
G01X1047237Y-161926D02*
Y-179426D01*
X1055971D01*
G01X1063645D02*
X1069104Y-161926D01*
X1074563Y-179426D01*
G01X1072597Y-173301D02*
X1065610D01*
G01X1081801Y-161926D02*
Y-174468D01*
X1082674Y-177093D01*
X1084421Y-178843D01*
X1086604Y-179426D01*
X1088787Y-178843D01*
X1090534Y-177093D01*
X1091407Y-174468D01*
Y-161926D01*
G01X941801Y-134426D02*
Y-116926D01*
X946167D01*
X947914Y-117801D01*
X949224Y-118968D01*
X950316Y-120717D01*
X951189Y-122760D01*
X951407Y-125676D01*
X951189Y-128593D01*
X950316Y-130635D01*
X949224Y-132385D01*
X947914Y-133551D01*
X946167Y-134426D01*
X941801D01*
G01X960829Y-126551D02*
X967816D01*
X967161Y-124509D01*
X966069Y-123343D01*
X964541Y-122760D01*
X963012Y-123051D01*
X961702Y-123926D01*
X960829Y-125968D01*
X960392Y-127718D01*
Y-129468D01*
X960829Y-131218D01*
X961921Y-132968D01*
X963231Y-134134D01*
X964759Y-134426D01*
X966287Y-133843D01*
X967816Y-132093D01*
G01X978329Y-132385D02*
X979421Y-133551D01*
X980949Y-134426D01*
X982259D01*
X983569Y-133843D01*
X984442Y-132968D01*
X984879Y-131802D01*
X984661Y-130051D01*
X983787Y-129176D01*
X979857Y-127426D01*
X978984Y-125384D01*
X979421Y-123926D01*
X980294Y-123051D01*
X981604Y-122760D01*
X982914Y-123051D01*
X984224Y-123926D01*
G01X999104Y-122760D02*
Y-134426D01*
G01Y-118093D02*
X998667Y-117801D01*
Y-117218D01*
X999104Y-116926D01*
X999541Y-117218D01*
Y-117801D01*
X999104Y-118093D01*
G01X1013547Y-138801D02*
X1015076Y-139968D01*
X1016822Y-140259D01*
X1018350Y-139968D01*
X1019661Y-138510D01*
X1020534Y-136468D01*
Y-122760D01*
G01Y-125093D02*
X1019661Y-123926D01*
X1018350Y-123051D01*
X1016822Y-122760D01*
X1015076Y-123343D01*
X1013984Y-124509D01*
X1013110Y-126551D01*
X1012674Y-128593D01*
X1012892Y-130343D01*
X1013766Y-132385D01*
X1015076Y-133843D01*
X1016822Y-134426D01*
X1018132Y-134134D01*
X1019661Y-132968D01*
X1020534Y-131802D01*
G01X1030392Y-134426D02*
Y-122760D01*
G01Y-125676D02*
X1031266Y-124218D01*
X1032576Y-123051D01*
X1034322Y-122760D01*
X1035850Y-123051D01*
X1037161Y-124218D01*
X1037816Y-126259D01*
Y-134426D01*
G01X1048329Y-126551D02*
X1055316D01*
X1054661Y-124509D01*
X1053569Y-123343D01*
X1052041Y-122760D01*
X1050512Y-123051D01*
X1049202Y-123926D01*
X1048329Y-125968D01*
X1047892Y-127718D01*
Y-129468D01*
X1048329Y-131218D01*
X1049421Y-132968D01*
X1050731Y-134134D01*
X1052259Y-134426D01*
X1053787Y-133843D01*
X1055316Y-132093D01*
G01X1066047Y-134426D02*
Y-122760D01*
G01Y-125093D02*
X1067139Y-123926D01*
X1068231Y-123051D01*
X1069759Y-122760D01*
X1070850Y-123051D01*
X1072161Y-123926D01*
G01X1112804Y-179426D02*
Y-161926D01*
X1110184Y-165426D01*
G01Y-179426D02*
X1115424D01*
G01X1130304D02*
Y-161926D01*
X1127684Y-165426D01*
G01Y-179426D02*
X1132924D01*
G01X1143874Y-180009D02*
X1151734Y-161926D01*
G01X1161156Y-164843D02*
X1162466Y-163093D01*
X1163994Y-162218D01*
X1165741Y-161926D01*
X1167924Y-162509D01*
X1169452Y-163968D01*
X1169889Y-165717D01*
X1169671Y-167468D01*
X1168797Y-168926D01*
X1164431Y-171843D01*
X1162466Y-173884D01*
X1161156Y-176802D01*
X1160719Y-179426D01*
X1169889D01*
G01X1178001Y-176802D02*
X1179310Y-178260D01*
X1180839Y-179134D01*
X1182804Y-179426D01*
X1184769Y-178843D01*
X1186297Y-177676D01*
X1187389Y-175635D01*
X1187607Y-173301D01*
X1187171Y-170968D01*
X1186079Y-169509D01*
X1184550Y-168343D01*
X1183022Y-168051D01*
X1181494Y-168343D01*
X1179529Y-169509D01*
X1180184Y-161926D01*
X1186079D01*
G01X1196374Y-180009D02*
X1204234Y-161926D01*
G01X1213656Y-164843D02*
X1214966Y-163093D01*
X1216494Y-162218D01*
X1218241Y-161926D01*
X1220424Y-162509D01*
X1221952Y-163968D01*
X1222389Y-165717D01*
X1222171Y-167468D01*
X1221297Y-168926D01*
X1216931Y-171843D01*
X1214966Y-173884D01*
X1213656Y-176802D01*
X1213219Y-179426D01*
X1222389D01*
G01X1235304Y-161926D02*
X1233557Y-162509D01*
X1232247Y-163968D01*
X1231374Y-165717D01*
X1230719Y-168051D01*
X1230501Y-170676D01*
X1230719Y-173301D01*
X1231374Y-175635D01*
X1232247Y-177385D01*
X1233557Y-178843D01*
X1235304Y-179426D01*
X1237050Y-178843D01*
X1238361Y-177385D01*
X1239234Y-175635D01*
X1239889Y-173301D01*
X1240107Y-170676D01*
X1239889Y-168051D01*
X1239234Y-165717D01*
X1238361Y-163968D01*
X1237050Y-162509D01*
X1235304Y-161926D01*
G01X1252804Y-179426D02*
Y-161926D01*
X1250184Y-165426D01*
G01Y-179426D02*
X1255424D01*
G01X1272924D02*
Y-161926D01*
X1264845Y-174468D01*
X1275763D01*
G01X1160501Y-134426D02*
Y-116926D01*
X1164867D01*
X1166614Y-117801D01*
X1167924Y-118968D01*
X1169016Y-120717D01*
X1169889Y-122760D01*
X1170107Y-125676D01*
X1169889Y-128593D01*
X1169016Y-130635D01*
X1167924Y-132385D01*
X1166614Y-133551D01*
X1164867Y-134426D01*
X1160501D01*
G01X1186734D02*
Y-122760D01*
G01Y-124801D02*
X1185861Y-123635D01*
X1184550Y-123051D01*
X1183022Y-122760D01*
X1181494Y-123343D01*
X1180184Y-124509D01*
X1179310Y-126259D01*
X1178874Y-128593D01*
X1179310Y-130926D01*
X1180184Y-132676D01*
X1181494Y-133843D01*
X1183022Y-134426D01*
X1184550Y-134134D01*
X1185861Y-133260D01*
X1186734Y-132093D01*
G01X1200304Y-116926D02*
Y-134426D01*
G01X1197247Y-122760D02*
X1203361D01*
G01X1214529Y-126551D02*
X1221516D01*
X1220861Y-124509D01*
X1219769Y-123343D01*
X1218241Y-122760D01*
X1216712Y-123051D01*
X1215402Y-123926D01*
X1214529Y-125968D01*
X1214092Y-127718D01*
Y-129468D01*
X1214529Y-131218D01*
X1215621Y-132968D01*
X1216931Y-134134D01*
X1218459Y-134426D01*
X1219987Y-133843D01*
X1221516Y-132093D01*
G54D13*
X-25005Y133422D03*
Y173422D03*
Y213422D03*
Y253422D03*
G54D14*
X-27555Y302202D03*
Y307202D03*
Y312202D03*
Y317202D03*
Y322202D03*
Y327202D03*
Y332202D03*
Y337202D03*
Y342202D03*
Y347202D03*
Y352202D03*
Y357202D03*
G54D15*
X-25005Y283072D03*
G54D16*
X-2722Y341000D03*
X1635Y347764D03*
X46898Y152936D03*
Y117936D03*
X47398Y214936D03*
X46898Y182936D03*
X48398Y274936D03*
X26500Y330436D03*
X20898Y325436D03*
X49398Y326436D03*
X20398Y309936D03*
X14000Y336000D03*
X53398Y388936D03*
X76000Y32000D03*
X73000Y94500D03*
X114398Y308936D03*
X78398Y371936D03*
X67398Y416936D03*
X189398Y115936D03*
X208398Y433436D03*
X248898Y35936D03*
X247898Y234936D03*
X282398Y312436D03*
X347898Y117436D03*
X365398Y35936D03*
X393241Y239988D03*
X394022Y308262D03*
X364398Y430936D03*
X444500Y445000D03*
X507398Y196436D03*
X489500Y352200D03*
X487039Y340243D03*
X477500Y370500D03*
X506500Y418500D03*
X525898Y33436D03*
X568691Y66413D03*
X526398Y116936D03*
X543000Y197500D03*
X534898Y261436D03*
X536398Y418936D03*
X579500Y333500D03*
X605398Y409436D03*
G54D17*
X570709Y161889D03*
X580709D03*
X570709Y214409D03*
X580709D03*
X570709Y204409D03*
X580709D03*
X570709Y191889D03*
X580709D03*
X570709Y181889D03*
X580709D03*
X570709Y171889D03*
X580709D03*
X570709Y244409D03*
X580709D03*
X570709Y276929D03*
X580709D03*
X570709Y266929D03*
X580709D03*
X570709Y256929D03*
X580709D03*
X570709Y234409D03*
X580709D03*
X570709Y224409D03*
X580709D03*
X570709Y286929D03*
X580709D03*
X590709Y161889D03*
X600709D03*
X590709Y214409D03*
X600709D03*
X590709Y204409D03*
X600709D03*
X590709Y191889D03*
X600709D03*
X590709Y181889D03*
X600709D03*
X590709Y171889D03*
X600709D03*
X590709Y244409D03*
X600709D03*
X590709Y276929D03*
X600709D03*
X590709Y266929D03*
X600709D03*
X590709Y256929D03*
X600709D03*
X590709Y234409D03*
X600709D03*
X590709Y224409D03*
X600709D03*
X590709Y286929D03*
X600709D03*
G54D18*
X559489Y427559D03*
X603780Y442126D03*
G54D19*
X571496Y433071D03*
X581339D03*
X591182D03*
M02*
